(kicad_pcb
	(version 20260206)
	(generator "pcbnew")
	(generator_version "10.0")
	(general
		(thickness 1.6)
		(legacy_teardrops no)
	)
	(paper "A4")
	(title_block
		(title "03242023_DA0F0TMBIJ0_F0T_Motherboard_J_brd_V01_OCP.brd")
		(comment 1 "Grand Teton / footprints 1661-1667 of 6105")
	)
	(layers
		(0 "F.Cu" signal "TOP")
		(4 "In1.Cu" signal "GND")
		(6 "In2.Cu" signal "IN1")
		(8 "In3.Cu" signal "GND1")
		(10 "In4.Cu" signal "IN2")
		(12 "In5.Cu" signal "GND2")
		(14 "In6.Cu" signal "IN3")
		(16 "In7.Cu" signal "GND3")
		(18 "In8.Cu" signal "VCC")
		(20 "In9.Cu" signal "VCC1")
		(22 "In10.Cu" signal "GND4")
		(24 "In11.Cu" signal "IN4")
		(26 "In12.Cu" signal "GND5")
		(28 "In13.Cu" signal "IN5")
		(30 "In14.Cu" signal "GND6")
		(32 "In15.Cu" signal "IN6")
		(34 "In16.Cu" signal "GND7")
		(2 "B.Cu" signal "BOTTOM")
		(9 "F.Adhes" user "F.Adhesive")
		(11 "B.Adhes" user "B.Adhesive")
		(13 "F.Paste" user "Package Geometry/Pastemask Top")
		(15 "B.Paste" user "Package Geometry/Pastemask Bottom")
		(5 "F.SilkS" user "Ref Des/Silkscreen Top")
		(7 "B.SilkS" user "Ref Des/Silkscreen Bottom")
		(1 "F.Mask" user "Board Geometry/Soldermask Top")
		(3 "B.Mask" user "Board Geometry/Soldermask Bottom")
		(17 "Dwgs.User" user "User.Drawings")
		(19 "Cmts.User" user "User.Comments")
		(21 "Eco1.User" user "User.Eco1")
		(23 "Eco2.User" user "User.Eco2")
		(25 "Edge.Cuts" user "Board Geometry/Outline")
		(27 "Margin" user)
		(31 "F.CrtYd" user "Package Geometry/Place Bound Top")
		(29 "B.CrtYd" user "Package Geometry/Place Bound Bottom")
		(35 "F.Fab" user "Ref Des/Assembly Top")
		(33 "B.Fab" user "Ref Des/Assembly Bottom")
	)
	(footprint ""
		(layer "F.Cu")
		(at 160.760918 -23.398226 180)
		(property "Reference" "R4150"
			(at 0 0 180)
			(layer "F.SilkS")
			(hide yes)
			(effects
				(font
					(size 1.27 1.27)
				)
			)
		)
		(property "Value" ""
			(at 0 0 180)
			(layer "F.Fab")
			(effects
				(font
					(size 1.27 1.27)
				)
			)
		)
		(duplicate_pad_numbers_are_jumpers no)
		(fp_line
			(start 0.7874 0.4064)
			(end -0.7874 0.4064)
			(stroke
				(width 0.1524)
				(type default)
			)
			(layer "F.SilkS")
		)
		(fp_line
			(start 0.7874 -0.4064)
			(end 0.7874 0.4064)
			(stroke
				(width 0.1524)
				(type default)
			)
			(layer "F.SilkS")
		)
		(fp_line
			(start -0.7874 0.4064)
			(end -0.7874 -0.4064)
			(stroke
				(width 0.1524)
				(type default)
			)
			(layer "F.SilkS")
		)
		(fp_line
			(start -0.7874 -0.4064)
			(end 0.7874 -0.4064)
			(stroke
				(width 0.1524)
				(type default)
			)
			(layer "F.SilkS")
		)
		(fp_line
			(start 0.67945 0.3048)
			(end 0.120396 0.3048)
			(stroke
				(width 0.1)
				(type default)
			)
			(layer "F.Fab")
		)
		(fp_line
			(start 0.67945 -0.3048)
			(end 0.67945 0.3048)
			(stroke
				(width 0.1)
				(type default)
			)
			(layer "F.Fab")
		)
		(fp_line
			(start 0.12065 -0.2794)
			(end 0.12065 -0.3048)
			(stroke
				(width 0.1)
				(type default)
			)
			(layer "F.Fab")
		)
		(fp_line
			(start 0.12065 -0.3048)
			(end 0.67945 -0.3048)
			(stroke
				(width 0.1)
				(type default)
			)
			(layer "F.Fab")
		)
		(fp_line
			(start 0.120396 0.3048)
			(end 0.120396 0.2794)
			(stroke
				(width 0.1)
				(type default)
			)
			(layer "F.Fab")
		)
		(fp_line
			(start 0.120396 0.2794)
			(end -0.12065 0.2794)
			(stroke
				(width 0.1)
				(type default)
			)
			(layer "F.Fab")
		)
		(fp_line
			(start -0.12065 0.3048)
			(end -0.67945 0.3048)
			(stroke
				(width 0.1)
				(type default)
			)
			(layer "F.Fab")
		)
		(fp_line
			(start -0.12065 0.2794)
			(end -0.12065 0.3048)
			(stroke
				(width 0.1)
				(type default)
			)
			(layer "F.Fab")
		)
		(fp_line
			(start -0.12065 -0.2794)
			(end 0.12065 -0.2794)
			(stroke
				(width 0.1)
				(type default)
			)
			(layer "F.Fab")
		)
		(fp_line
			(start -0.12065 -0.305054)
			(end -0.12065 -0.2794)
			(stroke
				(width 0.1)
				(type default)
			)
			(layer "F.Fab")
		)
		(fp_line
			(start -0.67945 0.3048)
			(end -0.67945 -0.305054)
			(stroke
				(width 0.1)
				(type default)
			)
			(layer "F.Fab")
		)
		(fp_line
			(start -0.67945 -0.305054)
			(end -0.12065 -0.305054)
			(stroke
				(width 0.1)
				(type default)
			)
			(layer "F.Fab")
		)
		(pad "1" smd circle
			(at -0.40005 0 180)
			(size 0 0)
			(layers "F.Cu" "F.Mask" "F.Paste")
			(net "SMB_1_PLD_3V3AUX_SDA")
		)
		(pad "2" smd circle
			(at 0.40005 0 180)
			(size 0 0)
			(layers "F.Cu" "F.Mask" "F.Paste")
			(net "SMB_1_PLD_3V3AUX_SDA_R1")
		)
	)
	(footprint ""
		(layer "F.Cu")
		(at 15.067788 -92.687648 90)
		(property "Reference" "R3659"
			(at 0 0 90)
			(layer "F.SilkS")
			(hide yes)
			(effects
				(font
					(size 1.27 1.27)
				)
			)
		)
		(property "Value" ""
			(at 0 0 90)
			(layer "F.Fab")
			(effects
				(font
					(size 1.27 1.27)
				)
			)
		)
		(duplicate_pad_numbers_are_jumpers no)
		(fp_line
			(start 0.7874 -0.4064)
			(end 0.7874 0.4064)
			(stroke
				(width 0.1524)
				(type default)
			)
			(layer "F.SilkS")
		)
		(fp_line
			(start -0.7874 -0.4064)
			(end 0.7874 -0.4064)
			(stroke
				(width 0.1524)
				(type default)
			)
			(layer "F.SilkS")
		)
		(fp_line
			(start 0.7874 0.4064)
			(end -0.7874 0.4064)
			(stroke
				(width 0.1524)
				(type default)
			)
			(layer "F.SilkS")
		)
		(fp_line
			(start -0.7874 0.4064)
			(end -0.7874 -0.4064)
			(stroke
				(width 0.1524)
				(type default)
			)
			(layer "F.SilkS")
		)
		(fp_line
			(start -0.12065 -0.305054)
			(end -0.12065 -0.2794)
			(stroke
				(width 0.1)
				(type default)
			)
			(layer "F.Fab")
		)
		(fp_line
			(start -0.67945 -0.305054)
			(end -0.12065 -0.305054)
			(stroke
				(width 0.1)
				(type default)
			)
			(layer "F.Fab")
		)
		(fp_line
			(start 0.67945 -0.3048)
			(end 0.67945 0.3048)
			(stroke
				(width 0.1)
				(type default)
			)
			(layer "F.Fab")
		)
		(fp_line
			(start 0.12065 -0.3048)
			(end 0.67945 -0.3048)
			(stroke
				(width 0.1)
				(type default)
			)
			(layer "F.Fab")
		)
		(fp_line
			(start 0.12065 -0.2794)
			(end 0.12065 -0.3048)
			(stroke
				(width 0.1)
				(type default)
			)
			(layer "F.Fab")
		)
		(fp_line
			(start -0.12065 -0.2794)
			(end 0.12065 -0.2794)
			(stroke
				(width 0.1)
				(type default)
			)
			(layer "F.Fab")
		)
		(fp_line
			(start 0.120396 0.2794)
			(end -0.12065 0.2794)
			(stroke
				(width 0.1)
				(type default)
			)
			(layer "F.Fab")
		)
		(fp_line
			(start -0.12065 0.2794)
			(end -0.12065 0.3048)
			(stroke
				(width 0.1)
				(type default)
			)
			(layer "F.Fab")
		)
		(fp_line
			(start 0.67945 0.3048)
			(end 0.120396 0.3048)
			(stroke
				(width 0.1)
				(type default)
			)
			(layer "F.Fab")
		)
		(fp_line
			(start 0.120396 0.3048)
			(end 0.120396 0.2794)
			(stroke
				(width 0.1)
				(type default)
			)
			(layer "F.Fab")
		)
		(fp_line
			(start -0.12065 0.3048)
			(end -0.67945 0.3048)
			(stroke
				(width 0.1)
				(type default)
			)
			(layer "F.Fab")
		)
		(fp_line
			(start -0.67945 0.3048)
			(end -0.67945 -0.305054)
			(stroke
				(width 0.1)
				(type default)
			)
			(layer "F.Fab")
		)
		(pad "1" smd circle
			(at -0.40005 0 90)
			(size 0 0)
			(layers "F.Cu" "F.Mask" "F.Paste")
			(net "P3V3_AUX")
		)
		(pad "2" smd circle
			(at 0.40005 0 90)
			(size 0 0)
			(layers "F.Cu" "F.Mask" "F.Paste")
			(net "USB_HUB_OVCUR4")
		)
	)
	(footprint ""
		(layer "F.Cu")
		(at 424.223942 -401.655534)
		(property "Reference" "R3470"
			(at 0 0 0)
			(layer "F.SilkS")
			(hide yes)
			(effects
				(font
					(size 1.27 1.27)
				)
			)
		)
		(property "Value" ""
			(at 0 0 0)
			(layer "F.Fab")
			(effects
				(font
					(size 1.27 1.27)
				)
			)
		)
		(duplicate_pad_numbers_are_jumpers no)
		(fp_line
			(start -0.7874 -0.4064)
			(end 0.7874 -0.4064)
			(stroke
				(width 0.1524)
				(type default)
			)
			(layer "F.SilkS")
		)
		(fp_line
			(start -0.7874 0.4064)
			(end -0.7874 -0.4064)
			(stroke
				(width 0.1524)
				(type default)
			)
			(layer "F.SilkS")
		)
		(fp_line
			(start 0.7874 -0.4064)
			(end 0.7874 0.4064)
			(stroke
				(width 0.1524)
				(type default)
			)
			(layer "F.SilkS")
		)
		(fp_line
			(start 0.7874 0.4064)
			(end -0.7874 0.4064)
			(stroke
				(width 0.1524)
				(type default)
			)
			(layer "F.SilkS")
		)
		(fp_line
			(start -0.67945 -0.305054)
			(end -0.12065 -0.305054)
			(stroke
				(width 0.1)
				(type default)
			)
			(layer "F.Fab")
		)
		(fp_line
			(start -0.67945 0.3048)
			(end -0.67945 -0.305054)
			(stroke
				(width 0.1)
				(type default)
			)
			(layer "F.Fab")
		)
		(fp_line
			(start -0.12065 -0.305054)
			(end -0.12065 -0.2794)
			(stroke
				(width 0.1)
				(type default)
			)
			(layer "F.Fab")
		)
		(fp_line
			(start -0.12065 -0.2794)
			(end 0.12065 -0.2794)
			(stroke
				(width 0.1)
				(type default)
			)
			(layer "F.Fab")
		)
		(fp_line
			(start -0.12065 0.2794)
			(end -0.12065 0.3048)
			(stroke
				(width 0.1)
				(type default)
			)
			(layer "F.Fab")
		)
		(fp_line
			(start -0.12065 0.3048)
			(end -0.67945 0.3048)
			(stroke
				(width 0.1)
				(type default)
			)
			(layer "F.Fab")
		)
		(fp_line
			(start 0.120396 0.2794)
			(end -0.12065 0.2794)
			(stroke
				(width 0.1)
				(type default)
			)
			(layer "F.Fab")
		)
		(fp_line
			(start 0.120396 0.3048)
			(end 0.120396 0.2794)
			(stroke
				(width 0.1)
				(type default)
			)
			(layer "F.Fab")
		)
		(fp_line
			(start 0.12065 -0.3048)
			(end 0.67945 -0.3048)
			(stroke
				(width 0.1)
				(type default)
			)
			(layer "F.Fab")
		)
		(fp_line
			(start 0.12065 -0.2794)
			(end 0.12065 -0.3048)
			(stroke
				(width 0.1)
				(type default)
			)
			(layer "F.Fab")
		)
		(fp_line
			(start 0.67945 -0.3048)
			(end 0.67945 0.3048)
			(stroke
				(width 0.1)
				(type default)
			)
			(layer "F.Fab")
		)
		(fp_line
			(start 0.67945 0.3048)
			(end 0.120396 0.3048)
			(stroke
				(width 0.1)
				(type default)
			)
			(layer "F.Fab")
		)
		(pad "1" smd circle
			(at -0.40005 0)
			(size 0 0)
			(layers "F.Cu" "F.Mask" "F.Paste")
			(net "P3V3_AUX")
		)
		(pad "2" smd circle
			(at 0.40005 0)
			(size 0 0)
			(layers "F.Cu" "F.Mask" "F.Paste")
			(net "GPU_WP_HW_CTRL_N")
		)
	)
	(footprint ""
		(layer "F.Cu")
		(at 69.397118 -402.371052 -90)
		(property "Reference" "C724"
			(at 0 0 270)
			(layer "F.SilkS")
			(hide yes)
			(effects
				(font
					(size 1.27 1.27)
				)
			)
		)
		(property "Value" ""
			(at 0 0 270)
			(layer "F.Fab")
			(effects
				(font
					(size 1.27 1.27)
				)
			)
		)
		(duplicate_pad_numbers_are_jumpers no)
		(fp_line
			(start -0.299974 0.150114)
			(end -0.299974 -0.150114)
			(stroke
				(width 0.1)
				(type default)
			)
			(layer "F.Fab")
		)
		(fp_line
			(start 0.299974 0.150114)
			(end -0.299974 0.150114)
			(stroke
				(width 0.1)
				(type default)
			)
			(layer "F.Fab")
		)
		(fp_line
			(start -0.299974 -0.150114)
			(end 0.299974 -0.150114)
			(stroke
				(width 0.1)
				(type default)
			)
			(layer "F.Fab")
		)
		(fp_line
			(start 0.299974 -0.150114)
			(end 0.299974 0.150114)
			(stroke
				(width 0.1)
				(type default)
			)
			(layer "F.Fab")
		)
		(pad "1" smd rect
			(at -0.2667 0 270)
			(size 0.3048 0.381)
			(layers "F.Cu" "F.Mask" "F.Paste")
			(net "P5E_CPU1_PE0_TX_C_DN<8>")
		)
		(pad "2" smd rect
			(at 0.2667 0 270)
			(size 0.3048 0.381)
			(layers "F.Cu" "F.Mask" "F.Paste")
			(net "P5E_CPU1_PE0_TX_DN<8>")
		)
	)
	(footprint ""
		(layer "F.Cu")
		(at 217.889582 -69.397118)
		(property "Reference" "PC2212"
			(at 0 0 0)
			(layer "F.SilkS")
			(hide yes)
			(effects
				(font
					(size 1.27 1.27)
				)
			)
		)
		(property "Value" ""
			(at 0 0 0)
			(layer "F.Fab")
			(effects
				(font
					(size 1.27 1.27)
				)
			)
		)
		(duplicate_pad_numbers_are_jumpers no)
		(fp_line
			(start -0.7874 -0.4064)
			(end 0.7874 -0.4064)
			(stroke
				(width 0.1524)
				(type default)
			)
			(layer "F.SilkS")
		)
		(fp_line
			(start -0.7874 0.4064)
			(end -0.7874 -0.4064)
			(stroke
				(width 0.1524)
				(type default)
			)
			(layer "F.SilkS")
		)
		(fp_line
			(start 0.7874 -0.4064)
			(end 0.7874 0.4064)
			(stroke
				(width 0.1524)
				(type default)
			)
			(layer "F.SilkS")
		)
		(fp_line
			(start 0.7874 0.4064)
			(end -0.7874 0.4064)
			(stroke
				(width 0.1524)
				(type default)
			)
			(layer "F.SilkS")
		)
		(fp_line
			(start -0.67945 -0.305054)
			(end -0.12065 -0.305054)
			(stroke
				(width 0.1)
				(type default)
			)
			(layer "F.Fab")
		)
		(fp_line
			(start -0.67945 0.3048)
			(end -0.67945 -0.305054)
			(stroke
				(width 0.1)
				(type default)
			)
			(layer "F.Fab")
		)
		(fp_line
			(start -0.12065 -0.305054)
			(end -0.12065 -0.2794)
			(stroke
				(width 0.1)
				(type default)
			)
			(layer "F.Fab")
		)
		(fp_line
			(start -0.12065 -0.2794)
			(end 0.12065 -0.2794)
			(stroke
				(width 0.1)
				(type default)
			)
			(layer "F.Fab")
		)
		(fp_line
			(start -0.12065 0.2794)
			(end -0.12065 0.3048)
			(stroke
				(width 0.1)
				(type default)
			)
			(layer "F.Fab")
		)
		(fp_line
			(start -0.12065 0.3048)
			(end -0.67945 0.3048)
			(stroke
				(width 0.1)
				(type default)
			)
			(layer "F.Fab")
		)
		(fp_line
			(start 0.120396 0.2794)
			(end -0.12065 0.2794)
			(stroke
				(width 0.1)
				(type default)
			)
			(layer "F.Fab")
		)
		(fp_line
			(start 0.120396 0.3048)
			(end 0.120396 0.2794)
			(stroke
				(width 0.1)
				(type default)
			)
			(layer "F.Fab")
		)
		(fp_line
			(start 0.12065 -0.3048)
			(end 0.67945 -0.3048)
			(stroke
				(width 0.1)
				(type default)
			)
			(layer "F.Fab")
		)
		(fp_line
			(start 0.12065 -0.2794)
			(end 0.12065 -0.3048)
			(stroke
				(width 0.1)
				(type default)
			)
			(layer "F.Fab")
		)
		(fp_line
			(start 0.67945 -0.3048)
			(end 0.67945 0.3048)
			(stroke
				(width 0.1)
				(type default)
			)
			(layer "F.Fab")
		)
		(fp_line
			(start 0.67945 0.3048)
			(end 0.120396 0.3048)
			(stroke
				(width 0.1)
				(type default)
			)
			(layer "F.Fab")
		)
		(pad "1" smd circle
			(at -0.40005 0)
			(size 0 0)
			(layers "F.Cu" "F.Mask" "F.Paste")
			(net "GND")
		)
		(pad "2" smd circle
			(at 0.40005 0)
			(size 0 0)
			(layers "F.Cu" "F.Mask" "F.Paste")
			(net "P3V3_E1S_REG_0")
		)
	)
	(footprint ""
		(layer "F.Cu")
		(at 92.7608 -33.061148)
		(property "Reference" "C2344"
			(at 0 0 0)
			(layer "F.SilkS")
			(hide yes)
			(effects
				(font
					(size 1.27 1.27)
				)
			)
		)
		(property "Value" ""
			(at 0 0 0)
			(layer "F.Fab")
			(effects
				(font
					(size 1.27 1.27)
				)
			)
		)
		(duplicate_pad_numbers_are_jumpers no)
		(fp_line
			(start -0.7874 -0.4064)
			(end 0.7874 -0.4064)
			(stroke
				(width 0.1524)
				(type default)
			)
			(layer "F.SilkS")
		)
		(fp_line
			(start -0.7874 0.4064)
			(end -0.7874 -0.4064)
			(stroke
				(width 0.1524)
				(type default)
			)
			(layer "F.SilkS")
		)
		(fp_line
			(start 0.7874 -0.4064)
			(end 0.7874 0.4064)
			(stroke
				(width 0.1524)
				(type default)
			)
			(layer "F.SilkS")
		)
		(fp_line
			(start 0.7874 0.4064)
			(end -0.7874 0.4064)
			(stroke
				(width 0.1524)
				(type default)
			)
			(layer "F.SilkS")
		)
		(fp_line
			(start -0.67945 -0.305054)
			(end -0.12065 -0.305054)
			(stroke
				(width 0.1)
				(type default)
			)
			(layer "F.Fab")
		)
		(fp_line
			(start -0.67945 0.3048)
			(end -0.67945 -0.305054)
			(stroke
				(width 0.1)
				(type default)
			)
			(layer "F.Fab")
		)
		(fp_line
			(start -0.12065 -0.305054)
			(end -0.12065 -0.2794)
			(stroke
				(width 0.1)
				(type default)
			)
			(layer "F.Fab")
		)
		(fp_line
			(start -0.12065 -0.2794)
			(end 0.12065 -0.2794)
			(stroke
				(width 0.1)
				(type default)
			)
			(layer "F.Fab")
		)
		(fp_line
			(start -0.12065 0.2794)
			(end -0.12065 0.3048)
			(stroke
				(width 0.1)
				(type default)
			)
			(layer "F.Fab")
		)
		(fp_line
			(start -0.12065 0.3048)
			(end -0.67945 0.3048)
			(stroke
				(width 0.1)
				(type default)
			)
			(layer "F.Fab")
		)
		(fp_line
			(start 0.120396 0.2794)
			(end -0.12065 0.2794)
			(stroke
				(width 0.1)
				(type default)
			)
			(layer "F.Fab")
		)
		(fp_line
			(start 0.120396 0.3048)
			(end 0.120396 0.2794)
			(stroke
				(width 0.1)
				(type default)
			)
			(layer "F.Fab")
		)
		(fp_line
			(start 0.12065 -0.3048)
			(end 0.67945 -0.3048)
			(stroke
				(width 0.1)
				(type default)
			)
			(layer "F.Fab")
		)
		(fp_line
			(start 0.12065 -0.2794)
			(end 0.12065 -0.3048)
			(stroke
				(width 0.1)
				(type default)
			)
			(layer "F.Fab")
		)
		(fp_line
			(start 0.67945 -0.3048)
			(end 0.67945 0.3048)
			(stroke
				(width 0.1)
				(type default)
			)
			(layer "F.Fab")
		)
		(fp_line
			(start 0.67945 0.3048)
			(end 0.120396 0.3048)
			(stroke
				(width 0.1)
				(type default)
			)
			(layer "F.Fab")
		)
		(pad "1" smd circle
			(at -0.40005 0)
			(size 0 0)
			(layers "F.Cu" "F.Mask" "F.Paste")
			(net "P3V3_AUX")
		)
		(pad "2" smd circle
			(at 0.40005 0)
			(size 0 0)
			(layers "F.Cu" "F.Mask" "F.Paste")
			(net "GND")
		)
	)
	(footprint ""
		(layer "F.Cu")
		(at 444.039498 -335.221072)
		(property "Reference" "U102"
			(at -0.5207 -2.466848 0)
			(unlocked yes)
			(layer "F.SilkS")
			(effects
				(font
					(size 0.7874 0.5842)
					(thickness 0.1524)
				)
				(justify left)
			)
		)
		(property "Value" ""
			(at 0 0 0)
			(layer "F.Fab")
			(effects
				(font
					(size 1.27 1.27)
				)
			)
		)
		(duplicate_pad_numbers_are_jumpers no)
		(fp_line
			(start -1.99263 -1.525016)
			(end -1.99263 1.525016)
			(stroke
				(width 0.1524)
				(type default)
			)
			(layer "F.SilkS")
		)
		(fp_line
			(start -1.99263 1.525016)
			(end 1.99263 1.525016)
			(stroke
				(width 0.1524)
				(type default)
			)
			(layer "F.SilkS")
		)
		(fp_line
			(start 1.99263 -1.525016)
			(end -1.99263 -1.525016)
			(stroke
				(width 0.1524)
				(type default)
			)
			(layer "F.SilkS")
		)
		(fp_line
			(start 1.99263 1.525016)
			(end 1.99263 -1.525016)
			(stroke
				(width 0.1524)
				(type default)
			)
			(layer "F.SilkS")
		)
		(fp_poly
			(pts
				(xy -0.843534 -2.815082) (xy -1.351534 -1.799082) (xy -1.859534 -2.815082)
			)
			(stroke
				(width 0)
				(type default)
			)
			(fill yes)
			(layer "F.SilkS")
		)
		(fp_line
			(start -0.87503 -1.525016)
			(end -0.87503 1.525016)
			(stroke
				(width 0.1)
				(type default)
			)
			(layer "F.Fab")
		)
		(fp_line
			(start -0.87503 1.525016)
			(end 0.87503 1.525016)
			(stroke
				(width 0.1)
				(type default)
			)
			(layer "F.Fab")
		)
		(fp_line
			(start 0.87503 -1.525016)
			(end -0.87503 -1.525016)
			(stroke
				(width 0.1)
				(type default)
			)
			(layer "F.Fab")
		)
		(fp_line
			(start 0.87503 1.525016)
			(end 0.87503 -1.525016)
			(stroke
				(width 0.1)
				(type default)
			)
			(layer "F.Fab")
		)
		(fp_poly
			(pts
				(xy -3.2004 -1.45796) (xy -3.2004 -0.44196) (xy -2.1844 -0.94996)
			)
			(stroke
				(width 0)
				(type default)
			)
			(fill yes)
			(layer "F.Fab")
		)
		(pad "1" smd circle
			(at -1.299972 -0.94996 270)
			(size 0 0)
			(layers "F.Cu" "F.Mask" "F.Paste")
			(net "GND")
		)
		(pad "2" smd circle
			(at -1.299972 0 270)
			(size 0 0)
			(layers "F.Cu" "F.Mask" "F.Paste")
			(net "GND")
		)
		(pad "3" smd circle
			(at -1.299972 0.94996 270)
			(size 0 0)
			(layers "F.Cu" "F.Mask" "F.Paste")
			(net "PVCCD_HV_CPU0_NVDIMM_ISENSE")
		)
		(pad "4" smd circle
			(at 1.299972 0.94996 270)
			(size 0 0)
			(layers "F.Cu" "F.Mask" "F.Paste")
			(net "P12V_AUX_CPU0_DIMM_ISEN_N")
		)
		(pad "5" smd circle
			(at 1.299972 -0.94996 270)
			(size 0 0)
			(layers "F.Cu" "F.Mask" "F.Paste")
			(net "P12V_AUX_CPU0_DIMM_ISEN_P")
		)
	)
)
